G04*
G04 #@! TF.GenerationSoftware,Altium Limited,Altium Designer,22.4.2 (48)*
G04*
G04 Layer_Color=32768*
%FSLAX25Y25*%
%MOIN*%
G70*
G04*
G04 #@! TF.SameCoordinates,446674BB-F454-490D-8607-5140536C8ADF*
G04*
G04*
G04 #@! TF.FilePolarity,Positive*
G04*
G01*
G75*
%ADD14C,0.00394*%
%ADD179C,0.00400*%
%ADD181C,0.00197*%
D14*
X341732Y-126772D02*
Y-122835D01*
X339764Y-124803D02*
X343701D01*
X363779Y-136221D02*
X367717D01*
X365748Y-138189D02*
Y-134252D01*
X639764Y-240945D02*
Y-237008D01*
X637795Y-238976D02*
X641732D01*
X554419Y-221374D02*
Y-217437D01*
X552450Y-219406D02*
X556387D01*
X602919Y-242874D02*
Y-238937D01*
X600950Y-240905D02*
X604887D01*
X586419Y-242874D02*
Y-238937D01*
X584450Y-240905D02*
X588387D01*
X596919Y-242874D02*
Y-238937D01*
X594950Y-240905D02*
X598887D01*
X591919Y-242874D02*
Y-238937D01*
X589950Y-240905D02*
X593887D01*
X571647Y-212906D02*
X575190D01*
X573419Y-214677D02*
Y-211134D01*
X646063Y-260236D02*
X650000D01*
X648032Y-262205D02*
Y-258268D01*
X362992Y-124803D02*
X366929D01*
X364961Y-126772D02*
Y-122835D01*
X639815Y-27805D02*
Y-23868D01*
X637846Y-25836D02*
X641783D01*
X81642Y-61860D02*
X85579D01*
X83610Y-63828D02*
Y-59891D01*
X258279Y-132277D02*
X261822D01*
X260050Y-134049D02*
Y-130506D01*
X243504Y-127165D02*
X247047D01*
X245276Y-128937D02*
Y-125394D01*
X47244Y-3839D02*
Y-98D01*
X45374Y-1969D02*
X49114D01*
X40354Y-3839D02*
Y-98D01*
X38484Y-1969D02*
X42224D01*
X33465Y-3839D02*
Y-98D01*
X31594Y-1969D02*
X35335D01*
X26575Y-3839D02*
Y-98D01*
X24705Y-1969D02*
X28445D01*
X101378Y-125984D02*
X105315D01*
X103347Y-127953D02*
Y-124016D01*
X-22736Y-192323D02*
Y-173622D01*
X-14469D01*
Y-192323D02*
Y-173622D01*
X-22736Y-192323D02*
X-14469D01*
X-22736Y-245079D02*
Y-226378D01*
X-14469D01*
Y-245079D02*
Y-226378D01*
X-22736Y-245079D02*
X-14469D01*
X-22736Y-298622D02*
Y-279921D01*
X-14469D01*
Y-298622D02*
Y-279921D01*
X-22736Y-298622D02*
X-14469D01*
X-22736Y-351378D02*
Y-332677D01*
X-14469D01*
Y-351378D02*
Y-332677D01*
X-22736Y-351378D02*
X-14469D01*
X79724Y-137697D02*
Y-133957D01*
X77854Y-135827D02*
X81595D01*
X80709Y-125984D02*
X84646D01*
X82677Y-127953D02*
Y-124016D01*
X73876Y-113740D02*
X77813D01*
X75845Y-115709D02*
Y-111772D01*
X44291Y-264764D02*
Y-260827D01*
X42323Y-262795D02*
X46260D01*
X44291Y-159449D02*
Y-155512D01*
X42323Y-157480D02*
X46260D01*
X72933Y-332677D02*
X76673D01*
X74803Y-334547D02*
Y-330807D01*
X80807Y-332677D02*
X84547D01*
X82677Y-334547D02*
Y-330807D01*
X44291Y-318898D02*
Y-314961D01*
X42323Y-316929D02*
X46260D01*
X44291Y-212598D02*
Y-208661D01*
X42323Y-210630D02*
X46260D01*
X55118Y-316929D02*
X58661D01*
X56890Y-318701D02*
Y-315158D01*
X56299Y-210630D02*
X59842D01*
X58071Y-212402D02*
Y-208858D01*
X56299Y-262795D02*
X59842D01*
X58071Y-264567D02*
Y-261024D01*
X73917Y-224409D02*
X77658D01*
X75787Y-226279D02*
Y-222539D01*
X80807Y-224410D02*
X84547D01*
X82677Y-226279D02*
Y-222539D01*
X81791Y-278543D02*
X85532D01*
X83661Y-280413D02*
Y-276673D01*
X73917Y-278543D02*
X77658D01*
X75787Y-280413D02*
Y-276673D01*
X72933Y-172244D02*
X76673D01*
X74803Y-174114D02*
Y-170374D01*
X80807Y-172244D02*
X84547D01*
X82677Y-174114D02*
Y-170374D01*
X-22736Y-118504D02*
Y-99803D01*
X-14469D01*
Y-118504D02*
Y-99803D01*
X-22736Y-118504D02*
X-14469D01*
X-22736Y-75197D02*
Y-56496D01*
X-14469D01*
Y-75197D02*
Y-56496D01*
X-22736Y-75197D02*
X-14469D01*
X500000Y-136860D02*
Y-132923D01*
X498032Y-134891D02*
X501968D01*
X482480Y-137647D02*
X486417D01*
X484449Y-139616D02*
Y-135679D01*
X456791Y-137647D02*
X460532D01*
X458661Y-139517D02*
Y-135777D01*
X647441Y-52017D02*
Y-48080D01*
X645472Y-50049D02*
X649409D01*
X612766Y-15985D02*
Y-12049D01*
X610798Y-14017D02*
X614735D01*
X65945Y-332677D02*
X69882D01*
X67913Y-334646D02*
Y-330709D01*
X27756Y-187795D02*
X41142D01*
X27596Y-171555D02*
X41094D01*
X34449Y-180315D02*
Y-179035D01*
X33858Y-179724D02*
X35039D01*
X27756Y-295472D02*
X41142D01*
X27596Y-279232D02*
X41094D01*
X34449Y-287992D02*
Y-286713D01*
X33858Y-287402D02*
X35039D01*
X197933Y-116978D02*
X201673D01*
X199803Y-118848D02*
Y-115108D01*
X399606Y-133612D02*
Y-129872D01*
X397736Y-131742D02*
X401476D01*
X264764Y-128592D02*
Y-125049D01*
X262992Y-126821D02*
X266535D01*
X287008Y-121447D02*
X290945D01*
X288976Y-123415D02*
Y-119478D01*
X216535Y-121899D02*
X220472D01*
X218504Y-123868D02*
Y-119931D01*
X563813Y-113177D02*
Y-109634D01*
X562042Y-111406D02*
X565585D01*
X599754Y-139173D02*
X603691D01*
X601723Y-141142D02*
Y-137205D01*
X579282Y-139173D02*
X583219D01*
X581250Y-141142D02*
Y-137205D01*
X586369Y-139173D02*
X590306D01*
X588337Y-141142D02*
Y-137205D01*
X593061Y-139173D02*
X596998D01*
X595030Y-141142D02*
Y-137205D01*
X542845Y-117405D02*
X546782D01*
X544813Y-119374D02*
Y-115437D01*
X112205Y-76624D02*
X116142D01*
X114173Y-78592D02*
Y-74655D01*
X96457Y-95324D02*
X100394D01*
X98425Y-97293D02*
Y-93356D01*
X346137Y-101482D02*
X350075D01*
X348106Y-103451D02*
Y-99514D01*
X445866Y-125836D02*
X449803D01*
X447835Y-127805D02*
Y-123868D01*
X264764Y-112057D02*
X268701D01*
X266732Y-114025D02*
Y-110088D01*
X244094Y-119931D02*
Y-115994D01*
X242126Y-117962D02*
X246063D01*
X67913Y-174213D02*
Y-170276D01*
X65945Y-172244D02*
X69882D01*
X68898Y-280512D02*
Y-276575D01*
X66929Y-278543D02*
X70866D01*
X68898Y-226378D02*
Y-222441D01*
X66929Y-224409D02*
X70866D01*
X513976Y-112057D02*
X517913D01*
X515945Y-114025D02*
Y-110088D01*
X528543Y-116781D02*
Y-112844D01*
X526575Y-114813D02*
X530512D01*
X264764Y-120718D02*
Y-117175D01*
X262992Y-118947D02*
X266535D01*
X235433Y-122883D02*
X238976D01*
X237205Y-124655D02*
Y-121112D01*
X57087Y-159252D02*
Y-155709D01*
X55315Y-157480D02*
X58858D01*
X405512Y-133612D02*
Y-129872D01*
X403642Y-131742D02*
X407382D01*
D179*
X611890Y-203622D02*
Y-143622D01*
X551890D02*
X611890D01*
X551890Y-203622D02*
Y-143622D01*
Y-203622D02*
X611890D01*
X557592Y-248012D02*
Y-218799D01*
X579246D01*
Y-248012D02*
Y-218799D01*
X557592Y-248012D02*
X579246D01*
X568419Y-234784D02*
Y-232028D01*
X567041Y-233405D02*
X569797D01*
X552419Y-233776D02*
Y-230035D01*
X550549Y-231906D02*
X554289D01*
X547694Y-229346D02*
X557143D01*
X547694Y-234465D02*
X557143D01*
X547694D02*
Y-229346D01*
X557143Y-234465D02*
Y-229346D01*
X550919Y-242874D02*
Y-238937D01*
X548950Y-240905D02*
X552887D01*
X543832Y-236968D02*
X558006D01*
X543832Y-244843D02*
X558006D01*
X543832D02*
Y-236968D01*
X558006Y-244843D02*
Y-236968D01*
X608950Y-240406D02*
X612887D01*
X610919Y-242374D02*
Y-238437D01*
X606982Y-247492D02*
Y-233319D01*
X614856Y-247492D02*
Y-233319D01*
X606982Y-247492D02*
X614856D01*
X606982Y-233319D02*
X614856D01*
X619950Y-240406D02*
X623887D01*
X621919Y-242374D02*
Y-238437D01*
X617982Y-247492D02*
Y-233319D01*
X625856Y-247492D02*
Y-233319D01*
X617982Y-247492D02*
X625856D01*
X617982Y-233319D02*
X625856D01*
X580265Y-230512D02*
X584005D01*
X582135Y-232382D02*
Y-228642D01*
X584694Y-235236D02*
Y-225787D01*
X579576Y-235236D02*
Y-225787D01*
X584694D01*
X579576Y-235236D02*
X584694D01*
X580549Y-219905D02*
X584289D01*
X582419Y-221776D02*
Y-218035D01*
X584978Y-224630D02*
Y-215181D01*
X579860Y-224630D02*
Y-215181D01*
X584978D01*
X579860Y-224630D02*
X584978D01*
X573474Y-208760D02*
Y-205020D01*
X571604Y-206890D02*
X575344D01*
X568750Y-204331D02*
X578198D01*
X568750Y-209449D02*
X578198D01*
X568750D02*
Y-204331D01*
X578198Y-209449D02*
Y-204331D01*
X565419Y-256776D02*
Y-253035D01*
X563549Y-254906D02*
X567289D01*
X559316Y-257858D02*
X571521D01*
X559316Y-251953D02*
X571521D01*
Y-257858D02*
Y-251953D01*
X559316Y-257858D02*
Y-251953D01*
X568919Y-304906D02*
X628919D01*
X568919D02*
Y-244905D01*
X628919D01*
Y-304906D02*
Y-244905D01*
X616516Y-206417D02*
Y-146417D01*
X701516D01*
X616516Y-206417D02*
X701516D01*
Y-146417D01*
X536556Y-333706D02*
Y-329769D01*
X534588Y-331738D02*
X538525D01*
X529469Y-335675D02*
X543643D01*
X529469Y-327801D02*
X543643D01*
Y-335675D02*
Y-327801D01*
X529469Y-335675D02*
Y-327801D01*
X536162Y-349848D02*
Y-345911D01*
X534194Y-347880D02*
X538131D01*
X529076Y-351817D02*
X543249D01*
X529076Y-343943D02*
X543249D01*
Y-351817D02*
Y-343943D01*
X529076Y-351817D02*
Y-343943D01*
X653150Y-342520D02*
X657087D01*
X655118Y-344488D02*
Y-340551D01*
X651181Y-349606D02*
Y-335433D01*
X659055Y-349606D02*
Y-335433D01*
X651181Y-349606D02*
X659055D01*
X651181Y-335433D02*
X659055D01*
X512540Y-337053D02*
Y-326423D01*
X526714Y-337053D02*
Y-326423D01*
X512540D02*
X526714D01*
X512540Y-337053D02*
X526714D01*
X517659Y-331738D02*
X521595D01*
X519627Y-333706D02*
Y-329769D01*
X512442Y-353195D02*
Y-342565D01*
X526615Y-353195D02*
Y-342565D01*
X512442D02*
X526615D01*
X512442Y-353195D02*
X526615D01*
X517560Y-347880D02*
X521497D01*
X519529Y-349848D02*
Y-345911D01*
X631693Y-317717D02*
X642323D01*
X631693Y-331890D02*
X642323D01*
Y-317717D01*
X631693Y-331890D02*
Y-317717D01*
X637008Y-326772D02*
Y-322835D01*
X635039Y-324803D02*
X638976D01*
X650394Y-317815D02*
X661024D01*
X650394Y-331988D02*
X661024D01*
Y-317815D01*
X650394Y-331988D02*
Y-317815D01*
X655709Y-326870D02*
Y-322933D01*
X653740Y-324902D02*
X657677D01*
X635039Y-342913D02*
X638976D01*
X637008Y-344882D02*
Y-340945D01*
X633071Y-350000D02*
Y-335827D01*
X640945Y-350000D02*
Y-335827D01*
X633071Y-350000D02*
X640945D01*
X633071Y-335827D02*
X640945D01*
X646457Y-237795D02*
X650394D01*
X648425Y-239764D02*
Y-235827D01*
X652362Y-244882D02*
Y-230709D01*
X644488Y-244882D02*
Y-230709D01*
X652362D01*
X644488Y-244882D02*
X652362D01*
X27596Y-187555D02*
Y-171555D01*
X41142Y-187795D02*
Y-171653D01*
X27596Y-295232D02*
Y-279232D01*
X41142Y-295472D02*
Y-279331D01*
X557935Y-130405D02*
X560691D01*
X559313Y-131783D02*
Y-129028D01*
X548487Y-145012D02*
X570140D01*
Y-115799D01*
X548487D02*
X570140D01*
X548487Y-145012D02*
Y-115799D01*
X569089Y-119765D02*
Y-114646D01*
X578538Y-119765D02*
Y-114646D01*
X569089D02*
X578538D01*
X569089Y-119765D02*
X578538D01*
X571943Y-117206D02*
X575683D01*
X573813Y-119076D02*
Y-115335D01*
X275787Y-356151D02*
X278150D01*
X276969Y-357332D02*
Y-354970D01*
X275197Y-359695D02*
Y-352608D01*
X278740Y-359695D02*
Y-352608D01*
X275197Y-359695D02*
X278740D01*
X275197Y-352608D02*
X278740D01*
X656299Y-252165D02*
Y-247047D01*
X646850Y-252165D02*
Y-247047D01*
Y-252165D02*
X656299D01*
X646850Y-247047D02*
X656299D01*
X649705Y-249606D02*
X653445D01*
X651575Y-251476D02*
Y-247736D01*
X355512Y-100394D02*
X359449D01*
X357480Y-102362D02*
Y-98425D01*
X361417Y-107480D02*
Y-93307D01*
X353543Y-107480D02*
Y-93307D01*
X361417D01*
X353543Y-107480D02*
X361417D01*
X271472Y-384340D02*
X275410D01*
X271472Y-376860D02*
X275410D01*
Y-384340D02*
Y-376860D01*
X271472Y-384340D02*
Y-376860D01*
X273441Y-381781D02*
Y-379419D01*
X272260Y-380600D02*
X274622D01*
X546555Y-153937D02*
X550295D01*
X548425Y-155807D02*
Y-152067D01*
X545472Y-160039D02*
Y-147835D01*
X551378Y-160039D02*
Y-147835D01*
X545472Y-160039D02*
X551378D01*
X545472Y-147835D02*
X551378D01*
X549400Y-142342D02*
Y-134468D01*
X535227Y-142342D02*
Y-134468D01*
Y-142342D02*
X549400D01*
X535227Y-134468D02*
X549400D01*
X540345Y-138406D02*
X544282D01*
X542313Y-140374D02*
Y-136437D01*
X615896Y-136417D02*
Y-128543D01*
X630069Y-136417D02*
Y-128543D01*
X615896D02*
X630069D01*
X615896Y-136417D02*
X630069D01*
X621014Y-132480D02*
X624951D01*
X622983Y-134449D02*
Y-130512D01*
X615896Y-145079D02*
Y-137205D01*
X630069Y-145079D02*
Y-137205D01*
X615896D02*
X630069D01*
X615896Y-145079D02*
X630069D01*
X621014Y-141142D02*
X624951D01*
X622983Y-143110D02*
Y-139173D01*
X205260Y-380600D02*
X207622D01*
X206441Y-381781D02*
Y-379419D01*
X204472Y-384340D02*
Y-376860D01*
X208410Y-384340D02*
Y-376860D01*
X204472D02*
X208410D01*
X204472Y-384340D02*
X208410D01*
X208472D02*
X212409D01*
X208472Y-376860D02*
X212409D01*
Y-384340D02*
Y-376860D01*
X208472Y-384340D02*
Y-376860D01*
X210441Y-381781D02*
Y-379419D01*
X209260Y-380600D02*
X211622D01*
X217160D02*
X219522D01*
X218341Y-381781D02*
Y-379419D01*
X216372Y-384340D02*
Y-376860D01*
X220309Y-384340D02*
Y-376860D01*
X216372D02*
X220309D01*
X216372Y-384340D02*
X220309D01*
X220672D02*
X224609D01*
X220672Y-376860D02*
X224609D01*
Y-384340D02*
Y-376860D01*
X220672Y-384340D02*
Y-376860D01*
X222641Y-381781D02*
Y-379419D01*
X221460Y-380600D02*
X223822D01*
X235972Y-384340D02*
X239910D01*
X235972Y-376860D02*
X239910D01*
Y-384340D02*
Y-376860D01*
X235972Y-384340D02*
Y-376860D01*
X237941Y-381781D02*
Y-379419D01*
X236760Y-380600D02*
X239122D01*
X239972Y-384340D02*
X243910D01*
X239972Y-376860D02*
X243910D01*
Y-384340D02*
Y-376860D01*
X239972Y-384340D02*
Y-376860D01*
X241941Y-381781D02*
Y-379419D01*
X240760Y-380600D02*
X243122D01*
X251472Y-384340D02*
X255410D01*
X251472Y-376860D02*
X255410D01*
Y-384340D02*
Y-376860D01*
X251472Y-384340D02*
Y-376860D01*
X253441Y-381781D02*
Y-379419D01*
X252260Y-380600D02*
X254622D01*
X255760D02*
X258122D01*
X256941Y-381781D02*
Y-379419D01*
X254972Y-384340D02*
Y-376860D01*
X258910Y-384340D02*
Y-376860D01*
X254972D02*
X258910D01*
X254972Y-384340D02*
X258910D01*
X267472D02*
X271410D01*
X267472Y-376860D02*
X271410D01*
Y-384340D02*
Y-376860D01*
X267472Y-384340D02*
Y-376860D01*
X269441Y-381781D02*
Y-379419D01*
X268260Y-380600D02*
X270622D01*
X620866Y-125984D02*
Y-122835D01*
X619291Y-124409D02*
X622441D01*
X614468Y-121653D02*
X627264D01*
X614468Y-127165D02*
X627264D01*
X614468D02*
Y-121653D01*
X627264Y-127165D02*
Y-121653D01*
X616290Y-120866D02*
Y-115748D01*
X625739Y-120866D02*
Y-115748D01*
X616290D02*
X625739D01*
X616290Y-120866D02*
X625739D01*
X619144Y-118307D02*
X622884D01*
X621014Y-120177D02*
Y-116437D01*
X543313Y-130276D02*
Y-126535D01*
X541443Y-128405D02*
X545184D01*
X538589Y-125847D02*
X548038D01*
X538589Y-130965D02*
X548038D01*
X538589D02*
Y-125847D01*
X548038Y-130965D02*
Y-125847D01*
X571900Y-138779D02*
X575640D01*
X573770Y-140650D02*
Y-136909D01*
X576329Y-143504D02*
Y-134055D01*
X571211Y-143504D02*
Y-134055D01*
X576329D01*
X571211Y-143504D02*
X576329D01*
X563928Y-107185D02*
Y-103445D01*
X562057Y-105315D02*
X565798D01*
X559203Y-102756D02*
X568652D01*
X559203Y-107874D02*
X568652D01*
X559203D02*
Y-102756D01*
X568652Y-107874D02*
Y-102756D01*
X113425Y-265502D02*
Y-261761D01*
X111555Y-263632D02*
X115295D01*
X108701Y-261072D02*
X118150D01*
X108701Y-266191D02*
X118150D01*
X108701D02*
Y-261072D01*
X118150Y-266191D02*
Y-261072D01*
X220669Y-356151D02*
X223031D01*
X221850Y-357332D02*
Y-354970D01*
X220079Y-359695D02*
Y-352608D01*
X223622Y-359695D02*
Y-352608D01*
X220079Y-359695D02*
X223622D01*
X220079Y-352608D02*
X223622D01*
D181*
X569403Y-233405D02*
G03*
X569403Y-233405I-984J0D01*
G01*
X560298Y-130405D02*
G03*
X560298Y-130405I-984J0D01*
G01*
X331102Y-119095D02*
X352362D01*
X331102Y-130512D02*
X352362D01*
X331102D02*
Y-119095D01*
X352362Y-130512D02*
Y-119095D01*
X355118Y-141929D02*
Y-130512D01*
X376378Y-141929D02*
Y-130512D01*
X355118D02*
X376378D01*
X355118Y-141929D02*
X376378D01*
X635630Y-232283D02*
X643898D01*
X635630Y-245669D02*
X643898D01*
Y-232283D01*
X635630Y-245669D02*
Y-232283D01*
X550285Y-212713D02*
X558553D01*
X550285Y-226098D02*
X558553D01*
Y-212713D01*
X550285Y-226098D02*
Y-212713D01*
X598785Y-247598D02*
X607053D01*
X598785Y-234213D02*
X607053D01*
X598785Y-247598D02*
Y-234213D01*
X607053Y-247598D02*
Y-234213D01*
X582285Y-247598D02*
X590553D01*
X582285Y-234213D02*
X590553D01*
X582285Y-247598D02*
Y-234213D01*
X590553Y-247598D02*
Y-234213D01*
X592785Y-247598D02*
X601053D01*
X592785Y-234213D02*
X601053D01*
X592785Y-247598D02*
Y-234213D01*
X601053Y-247598D02*
Y-234213D01*
X587785Y-247598D02*
X596053D01*
X587785Y-234213D02*
X596053D01*
X587785Y-247598D02*
Y-234213D01*
X596053Y-247598D02*
Y-234213D01*
X568104Y-215858D02*
Y-209953D01*
X578734Y-215858D02*
Y-209953D01*
X568104D02*
X578734D01*
X568104Y-215858D02*
X578734D01*
X658661Y-265945D02*
Y-254528D01*
X637402Y-265945D02*
Y-254528D01*
Y-265945D02*
X658661D01*
X637402Y-254528D02*
X658661D01*
X354331Y-130512D02*
Y-119095D01*
X375590Y-130512D02*
Y-119095D01*
X354331D02*
X375590D01*
X354331Y-130512D02*
X375590D01*
X626423Y-42726D02*
Y-8946D01*
X653207Y-42726D02*
Y-8946D01*
X626423D02*
X653207D01*
X626423Y-42726D02*
X653207D01*
X548307Y-354528D02*
X630276D01*
Y-305551D01*
X548307D02*
X630276D01*
X548307Y-354528D02*
Y-305551D01*
X70218Y-44970D02*
X97003D01*
X70218Y-78750D02*
X97003D01*
X70218D02*
Y-44970D01*
X97003Y-78750D02*
Y-44970D01*
X265168Y-135033D02*
Y-129521D01*
X254932Y-135033D02*
Y-129521D01*
Y-135033D02*
X265168D01*
X254932Y-129521D02*
X265168D01*
X250394Y-129921D02*
Y-124409D01*
X240158Y-129921D02*
Y-124409D01*
Y-129921D02*
X250394D01*
X240158Y-124409D02*
X250394D01*
X-54527Y-331505D02*
X6260D01*
Y-302057D01*
X-54527D02*
X6260D01*
X-54527Y-331505D02*
Y-302057D01*
X-54528Y-278354D02*
X6260D01*
Y-248905D01*
X-54528D02*
X6260D01*
X-54528Y-278354D02*
Y-248905D01*
Y-225205D02*
X6260D01*
Y-195756D01*
X-54528D02*
X6260D01*
X-54528Y-225205D02*
Y-195756D01*
X-54527Y-172057D02*
X6260D01*
Y-142608D01*
X-54527D02*
X6260D01*
X-54527Y-172057D02*
Y-142608D01*
X66929Y-217717D02*
X84646D01*
X66929D02*
Y-207480D01*
X84646D01*
Y-217717D02*
Y-207480D01*
X65945Y-164567D02*
X83661D01*
X65945D02*
Y-154331D01*
X83661D01*
Y-164567D02*
Y-154331D01*
X44291Y-7283D02*
X50197D01*
X44291Y3347D02*
X50197D01*
X44291Y-7283D02*
Y3347D01*
X50197Y-7283D02*
Y3347D01*
X37402Y-7283D02*
X43307D01*
X37402Y3347D02*
X43307D01*
X37402Y-7283D02*
Y3347D01*
X43307Y-7283D02*
Y3347D01*
X30512Y-7283D02*
X36417D01*
X30512Y3347D02*
X36417D01*
X30512Y-7283D02*
Y3347D01*
X36417Y-7283D02*
Y3347D01*
X23622Y-7283D02*
X29528D01*
X23622Y3347D02*
X29528D01*
X23622Y-7283D02*
Y3347D01*
X29528Y-7283D02*
Y3347D01*
X91240Y-138091D02*
Y-113878D01*
X115453Y-138091D02*
Y-113878D01*
X91240D02*
X115453D01*
X91240Y-138091D02*
X115453D01*
X73819Y-138779D02*
X85630D01*
X73819Y-132874D02*
X85630D01*
Y-138779D02*
Y-132874D01*
X73819Y-138779D02*
Y-132874D01*
X86811Y-132677D02*
Y-119291D01*
X78543Y-132677D02*
Y-119291D01*
X86811D01*
X78543Y-132677D02*
X86811D01*
X71711Y-120433D02*
Y-107047D01*
X79978Y-120433D02*
Y-107047D01*
X71711Y-120433D02*
X79978D01*
X71711Y-107047D02*
X79978D01*
X66929Y-269882D02*
X84646D01*
X66929D02*
Y-259646D01*
X84646D01*
Y-269882D02*
Y-259646D01*
X35827Y-271063D02*
Y-254528D01*
X50787D01*
X35827Y-271063D02*
X50787D01*
Y-254528D01*
X35827Y-165748D02*
Y-149213D01*
X50787D01*
X35827Y-165748D02*
X50787D01*
Y-149213D01*
X71850Y-338583D02*
Y-326772D01*
X77756Y-338583D02*
Y-326772D01*
X71850Y-338583D02*
X77756D01*
X71850Y-326772D02*
X77756D01*
X79724Y-338583D02*
Y-326772D01*
X85630Y-338583D02*
Y-326772D01*
X79724Y-338583D02*
X85630D01*
X79724Y-326772D02*
X85630D01*
X65945Y-324016D02*
X83661D01*
X65945D02*
Y-313779D01*
X83661D01*
Y-324016D02*
Y-313779D01*
X35827Y-325197D02*
Y-308661D01*
X50787D01*
X35827Y-325197D02*
X50787D01*
Y-308661D01*
X35827Y-218898D02*
Y-202362D01*
X50787D01*
X35827Y-218898D02*
X50787D01*
Y-202362D01*
X62008Y-319685D02*
Y-314173D01*
X51772Y-319685D02*
Y-314173D01*
Y-319685D02*
X62008D01*
X51772Y-314173D02*
X62008D01*
X63189Y-213386D02*
Y-207874D01*
X52953Y-213386D02*
Y-207874D01*
Y-213386D02*
X63189D01*
X52953Y-207874D02*
X63189D01*
Y-265551D02*
Y-260039D01*
X52953Y-265551D02*
Y-260039D01*
Y-265551D02*
X63189D01*
X52953Y-260039D02*
X63189D01*
X72835Y-230315D02*
Y-218504D01*
X78740Y-230315D02*
Y-218504D01*
X72835Y-230315D02*
X78740D01*
X72835Y-218504D02*
X78740D01*
X79724Y-230315D02*
Y-218504D01*
X85630Y-230315D02*
Y-218504D01*
X79724Y-230315D02*
X85630D01*
X79724Y-218504D02*
X85630D01*
X80709Y-284449D02*
Y-272638D01*
X86614Y-284449D02*
Y-272638D01*
X80709Y-284449D02*
X86614D01*
X80709Y-272638D02*
X86614D01*
X72835Y-284449D02*
Y-272638D01*
X78740Y-284449D02*
Y-272638D01*
X72835Y-284449D02*
X78740D01*
X72835Y-272638D02*
X78740D01*
X71850Y-178150D02*
Y-166339D01*
X77756Y-178150D02*
Y-166339D01*
X71850Y-178150D02*
X77756D01*
X71850Y-166339D02*
X77756D01*
X79724Y-178150D02*
Y-166339D01*
X85630Y-178150D02*
Y-166339D01*
X79724Y-178150D02*
X85630D01*
X79724Y-166339D02*
X85630D01*
X495866Y-141584D02*
X504134D01*
X495866Y-128198D02*
X504134D01*
X495866Y-141584D02*
Y-128198D01*
X504134Y-141584D02*
Y-128198D01*
X491142Y-141781D02*
Y-133513D01*
X477756Y-141781D02*
Y-133513D01*
Y-141781D02*
X491142D01*
X477756Y-133513D02*
X491142D01*
X462795Y-140009D02*
Y-135285D01*
X454528Y-140009D02*
Y-135285D01*
Y-140009D02*
X462795D01*
X454528Y-135285D02*
X462795D01*
X640748Y-54183D02*
X654134D01*
X640748Y-45915D02*
X654134D01*
Y-54183D02*
Y-45915D01*
X640748Y-54183D02*
Y-45915D01*
X606074Y-18151D02*
X619459D01*
X606074Y-9883D02*
X619459D01*
Y-18151D02*
Y-9883D01*
X606074Y-18151D02*
Y-9883D01*
X63779Y-339370D02*
Y-325984D01*
X72047Y-339370D02*
Y-325984D01*
X63779Y-339370D02*
X72047D01*
X63779Y-325984D02*
X72047D01*
X196850Y-122096D02*
Y-111860D01*
X202756Y-122096D02*
Y-111860D01*
X196850Y-122096D02*
X202756D01*
X196850Y-111860D02*
X202756D01*
X396654Y-137647D02*
X402559D01*
X396654Y-125836D02*
X402559D01*
X396654Y-137647D02*
Y-125836D01*
X402559Y-137647D02*
Y-125836D01*
X260630Y-128986D02*
X268898D01*
X260630Y-124655D02*
X268898D01*
Y-128986D02*
Y-124655D01*
X260630Y-128986D02*
Y-124655D01*
X274213Y-132273D02*
Y-110620D01*
X303740Y-132273D02*
Y-110620D01*
X274213D02*
X303740D01*
X274213Y-132273D02*
X303740D01*
X205118Y-132135D02*
Y-111663D01*
X231890Y-132135D02*
Y-111663D01*
X205118D02*
X231890D01*
X205118Y-132135D02*
X231890D01*
X558498Y-114358D02*
X569128D01*
X558498Y-108453D02*
X569128D01*
Y-114358D02*
Y-108453D01*
X558498Y-114358D02*
Y-108453D01*
X605857Y-145866D02*
Y-132480D01*
X597589Y-145866D02*
Y-132480D01*
X605857D01*
X597589Y-145866D02*
X605857D01*
X585384D02*
Y-132480D01*
X577116Y-145866D02*
Y-132480D01*
X585384D01*
X577116Y-145866D02*
X585384D01*
X592471D02*
Y-132480D01*
X584203Y-145866D02*
Y-132480D01*
X592471D01*
X584203Y-145866D02*
X592471D01*
X599164D02*
Y-132480D01*
X590896Y-145866D02*
Y-132480D01*
X599164D01*
X590896Y-145866D02*
X599164D01*
X540680Y-124098D02*
Y-110713D01*
X548947Y-124098D02*
Y-110713D01*
X540680Y-124098D02*
X548947D01*
X540680Y-110713D02*
X548947D01*
X118307Y-83316D02*
Y-69931D01*
X110039Y-83316D02*
Y-69931D01*
X118307D01*
X110039Y-83316D02*
X118307D01*
X102559Y-102017D02*
Y-88631D01*
X94291Y-102017D02*
Y-88631D01*
X102559D01*
X94291Y-102017D02*
X102559D01*
X343972Y-108175D02*
Y-94789D01*
X352240Y-108175D02*
Y-94789D01*
X343972Y-108175D02*
X352240D01*
X343972Y-94789D02*
X352240D01*
X443701Y-132529D02*
Y-119143D01*
X451968Y-132529D02*
Y-119143D01*
X443701Y-132529D02*
X451968D01*
X443701Y-119143D02*
X451968D01*
X260039Y-116191D02*
Y-107923D01*
X273425Y-116191D02*
Y-107923D01*
X260039D02*
X273425D01*
X260039Y-116191D02*
X273425D01*
X239961Y-111269D02*
X248228D01*
X239961Y-124655D02*
X248228D01*
Y-111269D01*
X239961Y-124655D02*
Y-111269D01*
X63779Y-165551D02*
X72047D01*
X63779Y-178937D02*
X72047D01*
Y-165551D01*
X63779Y-178937D02*
Y-165551D01*
X64764Y-271850D02*
X73032D01*
X64764Y-285236D02*
X73032D01*
Y-271850D01*
X64764Y-285236D02*
Y-271850D01*
X64764Y-217717D02*
X73032D01*
X64764Y-231102D02*
X73032D01*
Y-217717D01*
X64764Y-231102D02*
Y-217717D01*
X522638Y-116191D02*
Y-107923D01*
X509252Y-116191D02*
Y-107923D01*
Y-116191D02*
X522638D01*
X509252Y-107923D02*
X522638D01*
X524409Y-108120D02*
X532677D01*
X524409Y-121505D02*
X532677D01*
Y-108120D01*
X524409Y-121505D02*
Y-108120D01*
X260630Y-121112D02*
X268898D01*
X260630Y-116781D02*
X268898D01*
Y-121112D02*
Y-116781D01*
X260630Y-121112D02*
Y-116781D01*
X234449Y-128002D02*
Y-117765D01*
X239961Y-128002D02*
Y-117765D01*
X234449Y-128002D02*
X239961D01*
X234449Y-117765D02*
X239961D01*
X51968Y-154724D02*
X62205D01*
X51968Y-160236D02*
X62205D01*
X51968D02*
Y-154724D01*
X62205Y-160236D02*
Y-154724D01*
X402559Y-137647D02*
X408465D01*
X402559Y-125836D02*
X408465D01*
X402559Y-137647D02*
Y-125836D01*
X408465Y-137647D02*
Y-125836D01*
M02*
